# T6G (Grand Teton) — schematic netlist excerpt (pin names and nets, part order shuffled) for the footprints in the layout excerpt that follows; sources: Cadence DE-HDL packaged netlist, KiCad conversion of 04192023_DAF0TMB3IC0_F0TG_MB_C_brd_V02_OCP.brd

R1583  Q_RES  49.9 1% CHIP  pkg 0402LF  page 101 : A = I3C_SPD_DDRAF_CPU1_SCL ; B = I3C_SPD_DDRD_CPU1_SCL
R981  Q_RES  4.7K 5% EMPTY  pkg 0201LF  page 276 : A = P1V8_CPU0_RT_1D ; B = TEST0_RT_CPU0_P0
C2630  Q_CAP  22UF 4V 20% X6S  pkg C0402  page 70 : A = PVDD11_S3_P0 ; B = GND

(kicad_pcb
	(version 20260206)
	(generator "pcbnew")
	(generator_version "10.0")
	(general
		(thickness 1.6)
		(legacy_teardrops no)
	)
	(paper "A4")
	(title_block
		(title "04192023_DAF0TMB3IC0_F0TG_MB_C_brd_V02_OCP.brd")
		(comment 1 "Grand Teton / footprints 7295-7297 of 8354")
	)
	(layers
		(0 "F.Cu" signal "TOP")
		(4 "In1.Cu" signal "GND")
		(6 "In2.Cu" signal "IN1")
		(8 "In3.Cu" signal "GND1")
		(10 "In4.Cu" signal "IN2")
		(12 "In5.Cu" signal "GND2")
		(14 "In6.Cu" signal "IN3")
		(16 "In7.Cu" signal "GND3")
		(18 "In8.Cu" signal "VCC")
		(20 "In9.Cu" signal "VCC1")
		(22 "In10.Cu" signal "GND4")
		(24 "In11.Cu" signal "IN4")
		(26 "In12.Cu" signal "GND5")
		(28 "In13.Cu" signal "IN5")
		(30 "In14.Cu" signal "GND6")
		(32 "In15.Cu" signal "IN6")
		(34 "In16.Cu" signal "GND7")
		(2 "B.Cu" signal "BOTTOM")
		(9 "F.Adhes" user "F.Adhesive")
		(11 "B.Adhes" user "B.Adhesive")
		(13 "F.Paste" user "Package Geometry/Pastemask Top")
		(15 "B.Paste" user "Package Geometry/Pastemask Bottom")
		(5 "F.SilkS" user "Ref Des/Silkscreen Top")
		(7 "B.SilkS" user "Ref Des/Silkscreen Bottom")
		(1 "F.Mask" user "Board Geometry/Soldermask Top")
		(3 "B.Mask" user "Board Geometry/Soldermask Bottom")
		(17 "Dwgs.User" user "User.Drawings")
		(19 "Cmts.User" user "User.Comments")
		(21 "Eco1.User" user "User.Eco1")
		(23 "Eco2.User" user "User.Eco2")
		(25 "Edge.Cuts" user "Board Geometry/Outline")
		(27 "Margin" user)
		(31 "F.CrtYd" user "Package Geometry/Place Bound Top")
		(29 "B.CrtYd" user "Package Geometry/Place Bound Bottom")
		(35 "F.Fab" user "Ref Des/Assembly Top")
		(33 "B.Fab" user "Ref Des/Assembly Bottom")
	)
	(footprint ""
		(layer "B.Cu")
		(at 299.265594 -395.10716 180)
		(property "Reference" "R981"
			(at 0 0 0)
			(layer "B.SilkS")
			(hide yes)
			(effects
				(font
					(size 1.27 1.27)
				)
				(justify mirror)
			)
		)
		(property "Value" ""
			(at 0 0 0)
			(layer "B.Fab")
			(effects
				(font
					(size 1.27 1.27)
				)
				(justify mirror)
			)
		)
		(duplicate_pad_numbers_are_jumpers no)
		(fp_line
			(start 0.32512 0.175006)
			(end 0.32512 -0.175006)
			(stroke
				(width 0.1)
				(type default)
			)
			(layer "B.Fab")
		)
		(fp_line
			(start 0.32512 -0.175006)
			(end -0.32512 -0.175006)
			(stroke
				(width 0.1)
				(type default)
			)
			(layer "B.Fab")
		)
		(fp_line
			(start -0.32512 0.175006)
			(end 0.32512 0.175006)
			(stroke
				(width 0.1)
				(type default)
			)
			(layer "B.Fab")
		)
		(fp_line
			(start -0.32512 -0.175006)
			(end -0.32512 0.175006)
			(stroke
				(width 0.1)
				(type default)
			)
			(layer "B.Fab")
		)
		(pad "1" smd rect
			(at 0.2667 0)
			(size 0.3048 0.381)
			(layers "B.Cu" "B.Mask" "B.Paste")
			(net "P1V8_CPU0_RT_1D")
		)
		(pad "2" smd rect
			(at -0.2667 0 180)
			(size 0.3048 0.381)
			(layers "B.Cu" "B.Mask" "B.Paste")
			(net "TEST0_RT_CPU0_P0")
		)
	)
	(footprint ""
		(layer "B.Cu")
		(at 369.392454 -264.35431)
		(property "Reference" "C2630"
			(at 0 0 0)
			(layer "B.SilkS")
			(hide yes)
			(effects
				(font
					(size 1.27 1.27)
				)
				(justify mirror)
			)
		)
		(property "Value" ""
			(at 0 0 0)
			(layer "B.Fab")
			(effects
				(font
					(size 1.27 1.27)
				)
				(justify mirror)
			)
		)
		(duplicate_pad_numbers_are_jumpers no)
		(fp_line
			(start -0.7874 -0.4064)
			(end -0.7874 0.4064)
			(stroke
				(width 0.1524)
				(type default)
			)
			(layer "B.SilkS")
		)
		(fp_line
			(start -0.7874 0.4064)
			(end 0.7874 0.4064)
			(stroke
				(width 0.1524)
				(type default)
			)
			(layer "B.SilkS")
		)
		(fp_line
			(start 0.7874 -0.4064)
			(end -0.7874 -0.4064)
			(stroke
				(width 0.1524)
				(type default)
			)
			(layer "B.SilkS")
		)
		(fp_line
			(start 0.7874 0.4064)
			(end 0.7874 -0.4064)
			(stroke
				(width 0.1524)
				(type default)
			)
			(layer "B.SilkS")
		)
		(fp_line
			(start -0.67945 -0.3048)
			(end -0.67945 0.3048)
			(stroke
				(width 0.1)
				(type default)
			)
			(layer "B.Fab")
		)
		(fp_line
			(start -0.67945 0.3048)
			(end -0.120396 0.3048)
			(stroke
				(width 0.1)
				(type default)
			)
			(layer "B.Fab")
		)
		(fp_line
			(start -0.12065 -0.3048)
			(end -0.67945 -0.3048)
			(stroke
				(width 0.1)
				(type default)
			)
			(layer "B.Fab")
		)
		(fp_line
			(start -0.12065 -0.2794)
			(end -0.12065 -0.3048)
			(stroke
				(width 0.1)
				(type default)
			)
			(layer "B.Fab")
		)
		(fp_line
			(start -0.120396 0.2794)
			(end 0.12065 0.2794)
			(stroke
				(width 0.1)
				(type default)
			)
			(layer "B.Fab")
		)
		(fp_line
			(start -0.120396 0.3048)
			(end -0.120396 0.2794)
			(stroke
				(width 0.1)
				(type default)
			)
			(layer "B.Fab")
		)
		(fp_line
			(start 0.12065 -0.305054)
			(end 0.12065 -0.2794)
			(stroke
				(width 0.1)
				(type default)
			)
			(layer "B.Fab")
		)
		(fp_line
			(start 0.12065 -0.2794)
			(end -0.12065 -0.2794)
			(stroke
				(width 0.1)
				(type default)
			)
			(layer "B.Fab")
		)
		(fp_line
			(start 0.12065 0.2794)
			(end 0.12065 0.3048)
			(stroke
				(width 0.1)
				(type default)
			)
			(layer "B.Fab")
		)
		(fp_line
			(start 0.12065 0.3048)
			(end 0.67945 0.3048)
			(stroke
				(width 0.1)
				(type default)
			)
			(layer "B.Fab")
		)
		(fp_line
			(start 0.67945 -0.305054)
			(end 0.12065 -0.305054)
			(stroke
				(width 0.1)
				(type default)
			)
			(layer "B.Fab")
		)
		(fp_line
			(start 0.67945 0.3048)
			(end 0.67945 -0.305054)
			(stroke
				(width 0.1)
				(type default)
			)
			(layer "B.Fab")
		)
		(pad "1" smd circle
			(at 0.40005 0 180)
			(size 0 0)
			(layers "B.Cu" "B.Mask" "B.Paste")
			(net "PVDD11_S3_P0")
		)
		(pad "2" smd circle
			(at -0.40005 0 180)
			(size 0 0)
			(layers "B.Cu" "B.Mask" "B.Paste")
			(net "GND")
		)
	)
	(footprint ""
		(layer "B.Cu")
		(at 36.040568 -194.9196 180)
		(property "Reference" "R1583"
			(at 0 0 0)
			(layer "B.SilkS")
			(hide yes)
			(effects
				(font
					(size 1.27 1.27)
				)
				(justify mirror)
			)
		)
		(property "Value" ""
			(at 0 0 0)
			(layer "B.Fab")
			(effects
				(font
					(size 1.27 1.27)
				)
				(justify mirror)
			)
		)
		(duplicate_pad_numbers_are_jumpers no)
		(fp_line
			(start 0.7874 0.4064)
			(end 0.7874 -0.4064)
			(stroke
				(width 0.1524)
				(type default)
			)
			(layer "B.SilkS")
		)
		(fp_line
			(start 0.7874 -0.4064)
			(end -0.7874 -0.4064)
			(stroke
				(width 0.1524)
				(type default)
			)
			(layer "B.SilkS")
		)
		(fp_line
			(start -0.7874 0.4064)
			(end 0.7874 0.4064)
			(stroke
				(width 0.1524)
				(type default)
			)
			(layer "B.SilkS")
		)
		(fp_line
			(start -0.7874 -0.4064)
			(end -0.7874 0.4064)
			(stroke
				(width 0.1524)
				(type default)
			)
			(layer "B.SilkS")
		)
		(fp_line
			(start 0.67945 0.3048)
			(end 0.67945 -0.305054)
			(stroke
				(width 0.1)
				(type default)
			)
			(layer "B.Fab")
		)
		(fp_line
			(start 0.67945 -0.305054)
			(end 0.12065 -0.305054)
			(stroke
				(width 0.1)
				(type default)
			)
			(layer "B.Fab")
		)
		(fp_line
			(start 0.12065 0.3048)
			(end 0.67945 0.3048)
			(stroke
				(width 0.1)
				(type default)
			)
			(layer "B.Fab")
		)
		(fp_line
			(start 0.12065 0.2794)
			(end 0.12065 0.3048)
			(stroke
				(width 0.1)
				(type default)
			)
			(layer "B.Fab")
		)
		(fp_line
			(start 0.12065 -0.2794)
			(end -0.12065 -0.2794)
			(stroke
				(width 0.1)
				(type default)
			)
			(layer "B.Fab")
		)
		(fp_line
			(start 0.12065 -0.305054)
			(end 0.12065 -0.2794)
			(stroke
				(width 0.1)
				(type default)
			)
			(layer "B.Fab")
		)
		(fp_line
			(start -0.120396 0.3048)
			(end -0.120396 0.2794)
			(stroke
				(width 0.1)
				(type default)
			)
			(layer "B.Fab")
		)
		(fp_line
			(start -0.120396 0.2794)
			(end 0.12065 0.2794)
			(stroke
				(width 0.1)
				(type default)
			)
			(layer "B.Fab")
		)
		(fp_line
			(start -0.12065 -0.2794)
			(end -0.12065 -0.3048)
			(stroke
				(width 0.1)
				(type default)
			)
			(layer "B.Fab")
		)
		(fp_line
			(start -0.12065 -0.3048)
			(end -0.67945 -0.3048)
			(stroke
				(width 0.1)
				(type default)
			)
			(layer "B.Fab")
		)
		(fp_line
			(start -0.67945 0.3048)
			(end -0.120396 0.3048)
			(stroke
				(width 0.1)
				(type default)
			)
			(layer "B.Fab")
		)
		(fp_line
			(start -0.67945 -0.3048)
			(end -0.67945 0.3048)
			(stroke
				(width 0.1)
				(type default)
			)
			(layer "B.Fab")
		)
		(pad "1" smd circle
			(at 0.40005 0)
			(size 0 0)
			(layers "B.Cu" "B.Mask" "B.Paste")
			(net "I3C_SPD_DDRAF_CPU1_SCL")
		)
		(pad "2" smd circle
			(at -0.40005 0)
			(size 0 0)
			(layers "B.Cu" "B.Mask" "B.Paste")
			(net "I3C_SPD_DDRD_CPU1_SCL")
		)
	)
)
